(kicad_pcb
	(version 20241229)
	(generator "pcbnew")
	(generator_version "9.0")
	(general
		(thickness 1.711)
		(legacy_teardrops no)
	)
	(paper "A4")
	(title_block
		(title "Antmicro Baseboard for Jetson AGX Thor")
		(date "2026-02-18")
		(rev "1.1.0")
		(company "Antmicro Ltd")
		(comment 1 "www.antmicro.com")
		(comment 9 "footprints 138-141 of 1170")
	)
	(layers
		(0 "F.Cu" signal)
		(4 "In1.Cu" signal)
		(6 "In2.Cu" signal)
		(8 "In3.Cu" signal)
		(10 "In4.Cu" jumper)
		(12 "In5.Cu" signal)
		(14 "In6.Cu" signal)
		(16 "In7.Cu" signal)
		(18 "In8.Cu" signal)
		(2 "B.Cu" signal)
		(9 "F.Adhes" user "F.Adhesive")
		(11 "B.Adhes" user "B.Adhesive")
		(13 "F.Paste" user)
		(15 "B.Paste" user)
		(5 "F.SilkS" user "F.Silkscreen")
		(7 "B.SilkS" user "B.Silkscreen")
		(1 "F.Mask" user)
		(3 "B.Mask" user)
		(17 "Dwgs.User" user "User.Drawings")
		(19 "Cmts.User" user "User.Comments")
		(21 "Eco1.User" user "User.Eco1")
		(23 "Eco2.User" user "User.Eco2")
		(25 "Edge.Cuts" user)
		(27 "Margin" user)
		(31 "F.CrtYd" user "F.Courtyard")
		(29 "B.CrtYd" user "B.Courtyard")
		(35 "F.Fab" user)
		(33 "B.Fab" user)
	)
	(footprint "antmicro-footprints:R_0402_1005Metric"
		(layer "F.Cu")
		(at 136 110.1 180)
		(descr "Resistor SMD 0402")
		(tags "resistor SMD 0402")
		(property "Reference" "R347"
			(at 1 0.3 0)
			(layer "F.SilkS")
			(effects
				(font
					(size 0.7 0.7)
					(thickness 0.15)
				)
				(justify right top)
			)
		)
		(property "Value" "R_0R_0402"
			(at -1.011843 1.772047 0)
			(layer "F.Fab")
			(effects
				(font
					(size 0.7 0.7)
					(thickness 0.15)
				)
				(justify right top)
			)
		)
		(property "Datasheet" "https://industrial.panasonic.com/cdbs/www-data/pdf/RDA0000/AOA0000C301.pdf"
			(at 0 0 0)
			(layer "F.Fab")
			(hide yes)
			(effects
				(font
					(size 1.27 1.27)
					(thickness 0.15)
				)
			)
		)
		(property "Description" "SMD Chip Resistor, Jumper, 0 ohm, 100 mW, 0402 [1005 Metric], Thick Film, General Purpose"
			(at 0 0 0)
			(layer "F.Fab")
			(hide yes)
			(effects
				(font
					(size 1.27 1.27)
					(thickness 0.15)
				)
			)
		)
		(property "MPN" "ERJ2GE0R00X"
			(at 0 0 180)
			(unlocked yes)
			(layer "F.Fab")
			(hide yes)
			(effects
				(font
					(size 1 1)
					(thickness 0.15)
				)
			)
		)
		(property "Manufacturer" "Panasonic"
			(at 0 0 180)
			(unlocked yes)
			(layer "F.Fab")
			(hide yes)
			(effects
				(font
					(size 1 1)
					(thickness 0.15)
				)
			)
		)
		(property "License" "Apache-2.0"
			(at 0 0 180)
			(unlocked yes)
			(layer "F.Fab")
			(hide yes)
			(effects
				(font
					(size 1 1)
					(thickness 0.15)
				)
			)
		)
		(property "Author" "Antmicro"
			(at 0 0 180)
			(unlocked yes)
			(layer "F.Fab")
			(hide yes)
			(effects
				(font
					(size 1 1)
					(thickness 0.15)
				)
			)
		)
		(property "Val" "0R"
			(at 0 0 180)
			(unlocked yes)
			(layer "F.Fab")
			(hide yes)
			(effects
				(font
					(size 1 1)
					(thickness 0.15)
				)
			)
		)
		(property "Tolerance" "~"
			(at 0 0 180)
			(unlocked yes)
			(layer "F.Fab")
			(hide yes)
			(effects
				(font
					(size 1 1)
					(thickness 0.15)
				)
			)
		)
		(property "Current" "1A"
			(at 0 0 180)
			(unlocked yes)
			(layer "F.Fab")
			(hide yes)
			(effects
				(font
					(size 1 1)
					(thickness 0.15)
				)
			)
		)
		(sheetname "/Peripherals/")
		(sheetfile "peripherals.kicad_sch")
		(attr smd)
		(fp_rect
			(start -0.925 -0.47)
			(end 0.925 0.47)
			(stroke
				(width 0.05)
				(type default)
			)
			(fill no)
			(layer "F.CrtYd")
		)
		(fp_rect
			(start -0.5 -0.25)
			(end 0.5 0.25)
			(stroke
				(width 0.15)
				(type solid)
			)
			(fill no)
			(layer "F.Fab")
		)
		(fp_text user "${REFERENCE}"
			(at -0.95 3.168 0)
			(layer "F.Fab")
			(effects
				(font
					(size 0.7 0.7)
					(thickness 0.15)
				)
				(justify right top)
			)
		)
		(fp_text user "Author: Antmicro"
			(at -0.95 4.169 0)
			(layer "F.Fab")
			(effects
				(font
					(size 0.7 0.7)
					(thickness 0.15)
				)
				(justify right top)
			)
		)
		(fp_text user "License: Apache-2.0"
			(at -0.95 5.169 0)
			(layer "F.Fab")
			(effects
				(font
					(size 0.7 0.7)
					(thickness 0.15)
				)
				(justify right top)
			)
		)
		(pad "1" smd roundrect
			(at -0.48 0 180)
			(size 0.59 0.64)
			(layers "F.Cu" "F.Mask" "F.Paste")
			(roundrect_rratio 0.25)
			(net 1313 "/Peripherals/GPIOEX_P0_2")
			(pintype "passive")
		)
		(pad "2" smd roundrect
			(at 0.48 0 180)
			(size 0.59 0.64)
			(layers "F.Cu" "F.Mask" "F.Paste")
			(roundrect_rratio 0.25)
			(net 98 "/CSI/CAM_CTRL.CSIA_FLG")
			(pintype "passive")
		)
	)
	(footprint "antmicro-footprints:C_0402_1005Metric"
		(layer "F.Cu")
		(at 109.8 129.5)
		(descr "Capacitor SMD 0402")
		(tags "capacitor SMD 0402")
		(property "Reference" "C194"
			(at -0.9 -0.4 180)
			(layer "F.SilkS")
			(effects
				(font
					(size 0.7 0.7)
					(thickness 0.15)
				)
				(justify right top)
			)
		)
		(property "Value" "C_220n_0402"
			(at -1.022927 2.155213 180)
			(layer "F.Fab")
			(effects
				(font
					(size 0.7 0.7)
					(thickness 0.15)
				)
				(justify right top)
			)
		)
		(property "Datasheet" "https://www.yageo.com/en/Chart/Download/pdf/CC0402KRX5R6BB224"
			(at 0 0 180)
			(layer "F.Fab")
			(hide yes)
			(effects
				(font
					(size 1.27 1.27)
					(thickness 0.15)
				)
			)
		)
		(property "Description" "SMD Multilayer Ceramic Capacitor, 0.22 µF, 10 V, 0402 [1005 Metric], ± 10%, X5R, CC Series"
			(at 0 0 180)
			(layer "F.Fab")
			(hide yes)
			(effects
				(font
					(size 1.27 1.27)
					(thickness 0.15)
				)
			)
		)
		(property "MPN" "CC0402KRX5R6BB224"
			(at 0 0 180)
			(unlocked yes)
			(layer "F.Fab")
			(hide yes)
			(effects
				(font
					(size 1 1)
					(thickness 0.15)
				)
			)
		)
		(property "Val" "220n"
			(at 0 0 180)
			(unlocked yes)
			(layer "F.Fab")
			(hide yes)
			(effects
				(font
					(size 1 1)
					(thickness 0.15)
				)
			)
		)
		(property "Voltage" "25V"
			(at 0 0 180)
			(unlocked yes)
			(layer "F.Fab")
			(hide yes)
			(effects
				(font
					(size 1 1)
					(thickness 0.15)
				)
			)
		)
		(property "Dielectric" "X7R"
			(at 0 0 180)
			(unlocked yes)
			(layer "F.Fab")
			(hide yes)
			(effects
				(font
					(size 1 1)
					(thickness 0.15)
				)
			)
		)
		(property "Manufacturer" "YAGEO"
			(at 0 0 180)
			(unlocked yes)
			(layer "F.Fab")
			(hide yes)
			(effects
				(font
					(size 1 1)
					(thickness 0.15)
				)
			)
		)
		(property "License" "Apache-2.0"
			(at 0 0 180)
			(unlocked yes)
			(layer "F.Fab")
			(hide yes)
			(effects
				(font
					(size 1 1)
					(thickness 0.15)
				)
			)
		)
		(property "Author" "Antmicro"
			(at 0 0 180)
			(unlocked yes)
			(layer "F.Fab")
			(hide yes)
			(effects
				(font
					(size 1 1)
					(thickness 0.15)
				)
			)
		)
		(property "Public" "False"
			(at 0 0 180)
			(unlocked yes)
			(layer "F.Fab")
			(hide yes)
			(effects
				(font
					(size 1 1)
					(thickness 0.15)
				)
			)
		)
		(sheetname "/M.2/")
		(sheetfile "m2.kicad_sch")
		(attr smd)
		(fp_poly
			(pts
				(xy -0.925 -0.47) (xy -0.925 0.47) (xy 0.925 0.47) (xy 0.925 -0.47)
			)
			(stroke
				(width 0.05)
				(type default)
			)
			(fill no)
			(layer "F.CrtYd")
		)
		(fp_line
			(start -0.494 -0.25)
			(end 0.504 -0.25)
			(stroke
				(width 0.15)
				(type solid)
			)
			(layer "F.Fab")
		)
		(fp_line
			(start -0.494 0.248)
			(end -0.494 -0.25)
			(stroke
				(width 0.15)
				(type solid)
			)
			(layer "F.Fab")
		)
		(fp_line
			(start 0.504 -0.25)
			(end 0.504 0.248)
			(stroke
				(width 0.15)
				(type solid)
			)
			(layer "F.Fab")
		)
		(fp_line
			(start 0.504 0.248)
			(end -0.494 0.248)
			(stroke
				(width 0.15)
				(type solid)
			)
			(layer "F.Fab")
		)
		(fp_text user "${REFERENCE}"
			(at -0.939 4.599 180)
			(layer "F.Fab")
			(effects
				(font
					(size 0.7 0.7)
					(thickness 0.15)
				)
				(justify right top)
			)
		)
		(fp_text user "Author: Antmicro"
			(at -0.939 3.399 180)
			(layer "F.Fab")
			(effects
				(font
					(size 0.7 0.7)
					(thickness 0.15)
				)
				(justify right top)
			)
		)
		(fp_text user "License: Apache-2.0"
			(at -0.939 5.799 180)
			(layer "F.Fab")
			(effects
				(font
					(size 0.7 0.7)
					(thickness 0.15)
				)
				(justify right top)
			)
		)
		(pad "1" smd roundrect
			(at -0.48 0)
			(size 0.59 0.64)
			(layers "F.Cu" "F.Mask" "F.Paste")
			(roundrect_rratio 0.25)
			(net 15 "/M.2/PCIe_{C1x1}.TX0+")
			(pintype "passive")
		)
		(pad "2" smd roundrect
			(at 0.48 0)
			(size 0.59 0.64)
			(layers "F.Cu" "F.Mask" "F.Paste")
			(roundrect_rratio 0.25)
			(net 440 "/M.2/M2_E_PET0_P")
			(pintype "passive")
		)
	)
	(footprint "antmicro-footprints:SOT-23-8"
		(layer "F.Cu")
		(at 169.904468 137.22 -90)
		(descr "http://www.ti.com/lit/ds/symlink/ina219.pdf")
		(property "Reference" "U60"
			(at 1.18 -2.695532 90)
			(layer "F.SilkS")
			(effects
				(font
					(size 0.7 0.7)
					(thickness 0.15)
				)
				(justify left bottom)
			)
		)
		(property "Value" "INA219AIDCNR"
			(at -2.925 2.8 90)
			(layer "F.Fab")
			(effects
				(font
					(size 0.7 0.7)
					(thickness 0.15)
				)
				(justify right top)
			)
		)
		(property "Datasheet" "https://www.ti.com/lit/ds/symlink/ina219.pdf?ts=1713856455637&ref_url=https%253A%252F%252Fwww.mouser.es%252F"
			(at 0 0 90)
			(layer "F.Fab")
			(hide yes)
			(effects
				(font
					(size 1.27 1.27)
					(thickness 0.15)
				)
			)
		)
		(property "Description" "Zerø-Drift, Bidirectional Current/Power Monitor With I2C Interface"
			(at 0 0 90)
			(layer "F.Fab")
			(hide yes)
			(effects
				(font
					(size 1.27 1.27)
					(thickness 0.15)
				)
			)
		)
		(property "Manufacturer" "Texas Instruments"
			(at 0 0 270)
			(unlocked yes)
			(layer "F.Fab")
			(hide yes)
			(effects
				(font
					(size 1 1)
					(thickness 0.15)
				)
			)
		)
		(property "MPN" "INA219AIDCNR"
			(at 0 0 270)
			(unlocked yes)
			(layer "F.Fab")
			(hide yes)
			(effects
				(font
					(size 1 1)
					(thickness 0.15)
				)
			)
		)
		(property "Author" "Antmicro"
			(at 0 0 270)
			(unlocked yes)
			(layer "F.Fab")
			(hide yes)
			(effects
				(font
					(size 1 1)
					(thickness 0.15)
				)
			)
		)
		(property "License" "Apache-2.0"
			(at 0 0 270)
			(unlocked yes)
			(layer "F.Fab")
			(hide yes)
			(effects
				(font
					(size 1 1)
					(thickness 0.15)
				)
			)
		)
		(sheetname "/DCDC/")
		(sheetfile "dcdc.kicad_sch")
		(attr smd)
		(fp_line
			(start -0.987 1.6)
			(end -0.987 1.324)
			(stroke
				(width 0.15)
				(type solid)
			)
			(layer "F.SilkS")
		)
		(fp_line
			(start -0.613 1.6)
			(end -0.987 1.6)
			(stroke
				(width 0.15)
				(type solid)
			)
			(layer "F.SilkS")
		)
		(fp_line
			(start 1 1.6)
			(end 0.6 1.6)
			(stroke
				(width 0.15)
				(type solid)
			)
			(layer "F.SilkS")
		)
		(fp_line
			(start 1 1.3)
			(end 1 1.6)
			(stroke
				(width 0.15)
				(type solid)
			)
			(layer "F.SilkS")
		)
		(fp_line
			(start -1 -1.3)
			(end -1 -1.6)
			(stroke
				(width 0.15)
				(type solid)
			)
			(layer "F.SilkS")
		)
		(fp_line
			(start 1 -1.3)
			(end 1 -1.6)
			(stroke
				(width 0.15)
				(type solid)
			)
			(layer "F.SilkS")
		)
		(fp_line
			(start -1 -1.6)
			(end -0.6 -1.6)
			(stroke
				(width 0.15)
				(type solid)
			)
			(layer "F.SilkS")
		)
		(fp_line
			(start 1 -1.6)
			(end 0.625 -1.6)
			(stroke
				(width 0.15)
				(type solid)
			)
			(layer "F.SilkS")
		)
		(fp_circle
			(center -1.3 -1.4)
			(end -1.25 -1.4)
			(stroke
				(width 0.15)
				(type solid)
			)
			(fill yes)
			(layer "F.SilkS")
		)
		(fp_rect
			(start -1.9 -1.75)
			(end 1.898 1.75)
			(stroke
				(width 0.05)
				(type solid)
			)
			(fill no)
			(layer "F.CrtYd")
		)
		(fp_line
			(start -1.4 -1.25)
			(end -1.2 -1.45)
			(stroke
				(width 0.15)
				(type solid)
			)
			(layer "F.Fab")
		)
		(fp_rect
			(start -1.401 -1.45)
			(end 1.398 1.449)
			(stroke
				(width 0.15)
				(type solid)
			)
			(fill no)
			(layer "F.Fab")
		)
		(fp_text user "License: Apache-2.0"
			(at -2.925 6 90)
			(layer "F.Fab")
			(effects
				(font
					(size 0.7 0.7)
					(thickness 0.15)
				)
				(justify right top)
			)
		)
		(fp_text user "Author: Antmicro"
			(at -2.925 7.2 90)
			(layer "F.Fab")
			(effects
				(font
					(size 0.7 0.7)
					(thickness 0.15)
				)
				(justify right top)
			)
		)
		(fp_text user "${REFERENCE}"
			(at -2.925 4.8 90)
			(layer "F.Fab")
			(effects
				(font
					(size 0.7 0.7)
					(thickness 0.15)
				)
				(justify right top)
			)
		)
		(pad "1" smd roundrect
			(at -1.3 -0.975 180)
			(size 0.45 1.1)
			(layers "F.Cu" "F.Mask" "F.Paste")
			(roundrect_rratio 0.25)
			(net 1282 "Net-(U60-IN+)")
			(pinfunction "IN+")
			(pintype "passive")
		)
		(pad "2" smd roundrect
			(at -1.3 -0.325 180)
			(size 0.45 1.1)
			(layers "F.Cu" "F.Mask" "F.Paste")
			(roundrect_rratio 0.25)
			(net 1162 "Net-(U60-IN-)")
			(pinfunction "IN-")
			(pintype "passive")
		)
		(pad "3" smd roundrect
			(at -1.3 0.325 180)
			(size 0.45 1.1)
			(layers "F.Cu" "F.Mask" "F.Paste")
			(roundrect_rratio 0.25)
			(net 1 "GND")
			(pinfunction "GND")
			(pintype "power_in")
		)
		(pad "4" smd roundrect
			(at -1.3 0.975 180)
			(size 0.45 1.1)
			(layers "F.Cu" "F.Mask" "F.Paste")
			(roundrect_rratio 0.25)
			(net 4 "+3V3_AON")
			(pinfunction "V_{S}")
			(pintype "power_in")
		)
		(pad "5" smd roundrect
			(at 1.3 0.975 180)
			(size 0.45 1.1)
			(layers "F.Cu" "F.Mask" "F.Paste")
			(roundrect_rratio 0.25)
			(net 853 "/I2C_{SYS}.SCL")
			(pinfunction "SCL")
			(pintype "open_collector")
		)
		(pad "6" smd roundrect
			(at 1.3 0.325 180)
			(size 0.45 1.1)
			(layers "F.Cu" "F.Mask" "F.Paste")
			(roundrect_rratio 0.25)
			(net 850 "/I2C_{SYS}.SDA")
			(pinfunction "SDA")
			(pintype "open_collector")
		)
		(pad "7" smd roundrect
			(at 1.3 -0.325 180)
			(size 0.45 1.1)
			(layers "F.Cu" "F.Mask" "F.Paste")
			(roundrect_rratio 0.25)
			(net 850 "/I2C_{SYS}.SDA")
			(pinfunction "A0")
			(pintype "passive")
		)
		(pad "8" smd roundrect
			(at 1.3 -0.975 180)
			(size 0.45 1.1)
			(layers "F.Cu" "F.Mask" "F.Paste")
			(roundrect_rratio 0.25)
			(net 1 "GND")
			(pinfunction "A1")
			(pintype "passive")
		)
	)
	(footprint "antmicro-footprints:L_Coilcraft-XAL7070"
		(layer "F.Cu")
		(at 180 77.5 180)
		(property "Reference" "L4"
			(at -4.4 -2.2 90)
			(layer "F.SilkS")
			(effects
				(font
					(size 0.7 0.7)
					(thickness 0.15)
				)
				(justify right top)
			)
		)
		(property "Value" "L_3u3_15.1A_Coilcraft-XAL7070"
			(at 0 5.2 0)
			(layer "F.Fab")
			(effects
				(font
					(size 0.7 0.7)
					(thickness 0.15)
				)
				(justify right top)
			)
		)
		(property "Datasheet" "https://www.coilcraft.com/en-us/products/power/shielded-inductors/molded-inductor/xal/xal7070/xal7070-332/"
			(at 0 0 0)
			(layer "F.Fab")
			(hide yes)
			(effects
				(font
					(size 1.27 1.27)
					(thickness 0.15)
				)
			)
		)
		(property "Description" "Power Inductor (SMD), 3.3 µH, 15.1 A, Shielded, 19.4 A, XAL7070"
			(at 0 0 0)
			(layer "F.Fab")
			(hide yes)
			(effects
				(font
					(size 1.27 1.27)
					(thickness 0.15)
				)
			)
		)
		(property "Val" "3u3/15.1A"
			(at 0 0 180)
			(unlocked yes)
			(layer "F.Fab")
			(hide yes)
			(effects
				(font
					(size 1 1)
					(thickness 0.15)
				)
			)
		)
		(property "Manufacturer" "Coilcraft"
			(at 0 0 180)
			(unlocked yes)
			(layer "F.Fab")
			(hide yes)
			(effects
				(font
					(size 1 1)
					(thickness 0.15)
				)
			)
		)
		(property "MPN" "XAL7070-332MEB"
			(at 0 0 180)
			(unlocked yes)
			(layer "F.Fab")
			(hide yes)
			(effects
				(font
					(size 1 1)
					(thickness 0.15)
				)
			)
		)
		(property "ISat" "19.4 A"
			(at 0 0 180)
			(unlocked yes)
			(layer "F.Fab")
			(hide yes)
			(effects
				(font
					(size 1 1)
					(thickness 0.15)
				)
			)
		)
		(property "IMax" "15.1 A"
			(at 0 0 180)
			(unlocked yes)
			(layer "F.Fab")
			(hide yes)
			(effects
				(font
					(size 1 1)
					(thickness 0.15)
				)
			)
		)
		(property "Size" "7.7x8"
			(at 0 0 180)
			(unlocked yes)
			(layer "F.Fab")
			(hide yes)
			(effects
				(font
					(size 1 1)
					(thickness 0.15)
				)
			)
		)
		(property "Author" "Antmicro"
			(at 0 0 180)
			(unlocked yes)
			(layer "F.Fab")
			(hide yes)
			(effects
				(font
					(size 1 1)
					(thickness 0.15)
				)
			)
		)
		(property "License" "Apache-2.0"
			(at 0 0 180)
			(unlocked yes)
			(layer "F.Fab")
			(hide yes)
			(effects
				(font
					(size 1 1)
					(thickness 0.15)
				)
			)
		)
		(component_classes
			(class "DCDC_20V")
		)
		(sheetname "/DCDC/")
		(sheetfile "dcdc.kicad_sch")
		(attr smd)
		(fp_line
			(start 3.85 -4)
			(end 3.85 4)
			(stroke
				(width 0.15)
				(type solid)
			)
			(layer "F.SilkS")
		)
		(fp_line
			(start 3.85 -4)
			(end -3.85 -4)
			(stroke
				(width 0.15)
				(type solid)
			)
			(layer "F.SilkS")
		)
		(fp_line
			(start -3.85 4)
			(end 3.85 4)
			(stroke
				(width 0.15)
				(type solid)
			)
			(layer "F.SilkS")
		)
		(fp_line
			(start -3.85 4)
			(end -3.85 -4)
			(stroke
				(width 0.15)
				(type solid)
			)
			(layer "F.SilkS")
		)
		(fp_rect
			(start -4.09 -4.25)
			(end 4.09 4.25)
			(stroke
				(width 0.05)
				(type solid)
			)
			(fill no)
			(layer "F.CrtYd")
		)
		(fp_line
			(start 3.85 4)
			(end -3.85 4)
			(stroke
				(width 0.15)
				(type solid)
			)
			(layer "F.Fab")
		)
		(fp_line
			(start 3.85 -4)
			(end 3.85 4)
			(stroke
				(width 0.15)
				(type solid)
			)
			(layer "F.Fab")
		)
		(fp_line
			(start -3.85 4)
			(end -3.85 -4)
			(stroke
				(width 0.15)
				(type solid)
			)
			(layer "F.Fab")
		)
		(fp_line
			(start -3.85 -4)
			(end 3.85 -4)
			(stroke
				(width 0.15)
				(type solid)
			)
			(layer "F.Fab")
		)
		(fp_text user "${REFERENCE}"
			(at -4.09 8.4 0)
			(layer "F.Fab")
			(effects
				(font
					(size 0.7 0.7)
					(thickness 0.15)
				)
				(justify right top)
			)
		)
		(fp_text user "License: Apache-2.0"
			(at -4.09 9.6 0)
			(layer "F.Fab")
			(effects
				(font
					(size 0.7 0.7)
					(thickness 0.15)
				)
				(justify right top)
			)
		)
		(fp_text user "Author: Antmicro"
			(at -4.09 7.2 0)
			(layer "F.Fab")
			(effects
				(font
					(size 0.7 0.7)
					(thickness 0.15)
				)
				(justify right top)
			)
		)
		(pad "1" smd roundrect
			(at -2.41 0 180)
			(size 1.92 6.5)
			(layers "F.Cu" "F.Mask" "F.Paste")
			(roundrect_rratio 0.1)
			(net 1184 "/DCDC/20V_SW")
			(pintype "passive")
		)
		(pad "2" smd roundrect
			(at 2.41 0 180)
			(size 1.92 6.5)
			(layers "F.Cu" "F.Mask" "F.Paste")
			(roundrect_rratio 0.1)
			(net 1105 "/DCDC/20V_OUT")
			(pintype "passive")
		)
	)
)
